(kicad_pcb
	(version 20260206)
	(generator "pcbnew")
	(generator_version "10.0")
	(general
		(thickness 1.6)
		(legacy_teardrops no)
	)
	(paper "A4")
	(title_block
		(title "peb — Lightning_PEB_BRD.brd")
		(comment 1 "Lightning (Wiwynn / Facebook NVMe JBOF) / footprint 1535 of 2563 (CN15), pads 1-76 of 166")
	)
	(layers
		(0 "F.Cu" signal "TOP")
		(4 "In1.Cu" signal "L2GND")
		(6 "In2.Cu" signal "L3")
		(8 "In3.Cu" signal "L4VCC")
		(10 "In4.Cu" signal "L5VCC")
		(12 "In5.Cu" signal "L6")
		(14 "In6.Cu" signal "L7GND")
		(2 "B.Cu" signal "BOTTOM")
		(9 "F.Adhes" user "F.Adhesive")
		(11 "B.Adhes" user "B.Adhesive")
		(13 "F.Paste" user "Package Geometry/Pastemask Top")
		(15 "B.Paste" user "Package Geometry/Pastemask Bottom")
		(5 "F.SilkS" user "Ref Des/Silkscreen Top")
		(7 "B.SilkS" user "Ref Des/Silkscreen Bottom")
		(1 "F.Mask" user "Board Geometry/Soldermask Top")
		(3 "B.Mask" user "Board Geometry/Soldermask Bottom")
		(17 "Dwgs.User" user "User.Drawings")
		(19 "Cmts.User" user "User.Comments")
		(21 "Eco1.User" user "User.Eco1")
		(23 "Eco2.User" user "User.Eco2")
		(25 "Edge.Cuts" user "Board Geometry/Outline")
		(27 "Margin" user)
		(31 "F.CrtYd" user "Package Geometry/Place Bound Top")
		(29 "B.CrtYd" user "Package Geometry/Place Bound Bottom")
		(35 "F.Fab" user "Ref Des/Assembly Top")
		(33 "B.Fab" user "Ref Des/Assembly Bottom")
	)
	(footprint ""
		(layer "F.Cu")
		(at 152.634442 -9.53008)
		(property "Reference" "CN15"
			(at 0 0 0)
			(layer "F.SilkS")
			(hide yes)
			(effects
				(font
					(size 1.27 1.27)
				)
			)
		)
		(property "Value" "MLX-CONN144-12R-3-GP-U2"
			(at -33.7693 -12.9032 0)
			(unlocked yes)
			(layer "F.Fab")
			(hide yes)
			(effects
				(font
					(size 1.016 1.016)
					(thickness 0.1524)
				)
			)
		)
		(property "Device Type" "PREFIT-144P-459383U2H519"
			(at -33.7693 -14.4272 0)
			(unlocked yes)
			(layer "F.Fab")
			(hide yes)
			(effects
				(font
					(size 1.016 1.016)
					(thickness 0.1524)
				)
			)
		)
		(duplicate_pad_numbers_are_jumpers no)
		(pad "AA1" thru_hole circle
			(at -19.500088 -4.400042)
			(size 0.7366 0.7366)
			(drill 0.369824)
			(layers "*.Cu" "*.Mask")
			(remove_unused_layers no)
			(net "PCIE_REFCLK_H2_P_R")
			(clearance 0.1778)
			(thermal_gap 0.1778)
		)
		(pad "AA2" thru_hole circle
			(at -18.750026 -2.999994)
			(size 0.7366 0.7366)
			(drill 0.369824)
			(layers "*.Cu" "*.Mask")
			(remove_unused_layers no)
			(net "PCIE_REFCLK_H2_N_R")
			(clearance 0.1778)
			(thermal_gap 0.1778)
		)
		(pad "AA3" thru_hole circle
			(at -17.999964 -3.700018)
			(size 0.7366 0.7366)
			(drill 0.369824)
			(layers "*.Cu" "*.Mask")
			(remove_unused_layers no)
			(net "GND")
			(clearance 0.1778)
			(thermal_gap 0.1778)
		)
		(pad "AA4" thru_hole circle
			(at -17.249902 -4.400042)
			(size 0.7366 0.7366)
			(drill 0.369824)
			(layers "*.Cu" "*.Mask")
			(remove_unused_layers no)
			(net "PCIE_RX_P80")
			(clearance 0.1778)
			(thermal_gap 0.1778)
		)
		(pad "AA5" thru_hole circle
			(at -16.500094 -2.999994)
			(size 0.7366 0.7366)
			(drill 0.369824)
			(layers "*.Cu" "*.Mask")
			(remove_unused_layers no)
			(net "PCIE_RX_N80")
			(clearance 0.1778)
			(thermal_gap 0.1778)
		)
		(pad "AA6" thru_hole circle
			(at -15.750032 -3.700018)
			(size 0.7366 0.7366)
			(drill 0.369824)
			(layers "*.Cu" "*.Mask")
			(remove_unused_layers no)
			(net "GND")
			(clearance 0.1778)
			(thermal_gap 0.1778)
		)
		(pad "AA7" thru_hole circle
			(at -14.99997 -4.400042)
			(size 0.7366 0.7366)
			(drill 0.369824)
			(layers "*.Cu" "*.Mask")
			(remove_unused_layers no)
			(net "PCIE_RX_P83")
			(clearance 0.1778)
			(thermal_gap 0.1778)
		)
		(pad "AA8" thru_hole circle
			(at -14.249908 -2.999994)
			(size 0.7366 0.7366)
			(drill 0.369824)
			(layers "*.Cu" "*.Mask")
			(remove_unused_layers no)
			(net "PCIE_RX_N83")
			(clearance 0.1778)
			(thermal_gap 0.1778)
		)
		(pad "AA9" thru_hole circle
			(at -13.5001 -3.700018)
			(size 0.7366 0.7366)
			(drill 0.369824)
			(layers "*.Cu" "*.Mask")
			(remove_unused_layers no)
			(net "GND")
			(clearance 0.1778)
			(thermal_gap 0.1778)
		)
		(pad "AB1" thru_hole circle
			(at -19.500088 -8.199882)
			(size 0.7366 0.7366)
			(drill 0.369824)
			(layers "*.Cu" "*.Mask")
			(remove_unused_layers no)
			(net "HOST1_RST_N_C")
			(clearance 0.1778)
			(thermal_gap 0.1778)
		)
		(pad "AB2" thru_hole circle
			(at -18.750026 -6.800088)
			(size 0.7366 0.7366)
			(drill 0.369824)
			(layers "*.Cu" "*.Mask")
			(remove_unused_layers no)
			(net "8644_SDA_R_1")
			(clearance 0.1778)
			(thermal_gap 0.1778)
		)
		(pad "AB3" thru_hole circle
			(at -17.999964 -7.500112)
			(size 0.7366 0.7366)
			(drill 0.369824)
			(layers "*.Cu" "*.Mask")
			(remove_unused_layers no)
			(net "GND")
			(clearance 0.1778)
			(thermal_gap 0.1778)
		)
		(pad "AB4" thru_hole circle
			(at -17.249902 -8.199882)
			(size 0.7366 0.7366)
			(drill 0.369824)
			(layers "*.Cu" "*.Mask")
			(remove_unused_layers no)
			(net "PCIE_RX_P81")
			(clearance 0.1778)
			(thermal_gap 0.1778)
		)
		(pad "AB5" thru_hole circle
			(at -16.500094 -6.800088)
			(size 0.7366 0.7366)
			(drill 0.369824)
			(layers "*.Cu" "*.Mask")
			(remove_unused_layers no)
			(net "PCIE_RX_N81")
			(clearance 0.1778)
			(thermal_gap 0.1778)
		)
		(pad "AB6" thru_hole circle
			(at -15.750032 -7.500112)
			(size 0.7366 0.7366)
			(drill 0.369824)
			(layers "*.Cu" "*.Mask")
			(remove_unused_layers no)
			(net "GND")
			(clearance 0.1778)
			(thermal_gap 0.1778)
		)
		(pad "AB7" thru_hole circle
			(at -14.99997 -8.199882)
			(size 0.7366 0.7366)
			(drill 0.369824)
			(layers "*.Cu" "*.Mask")
			(remove_unused_layers no)
			(net "PCIE_RX_P82")
			(clearance 0.1778)
			(thermal_gap 0.1778)
		)
		(pad "AB8" thru_hole circle
			(at -14.249908 -6.800088)
			(size 0.7366 0.7366)
			(drill 0.369824)
			(layers "*.Cu" "*.Mask")
			(remove_unused_layers no)
			(net "PCIE_RX_N82")
			(clearance 0.1778)
			(thermal_gap 0.1778)
		)
		(pad "AB9" thru_hole circle
			(at -13.5001 -7.500112)
			(size 0.7366 0.7366)
			(drill 0.369824)
			(layers "*.Cu" "*.Mask")
			(remove_unused_layers no)
			(net "GND")
			(clearance 0.1778)
			(thermal_gap 0.1778)
		)
		(pad "AC1" thru_hole circle
			(at -19.500088 -11.999976)
			(size 0.7366 0.7366)
			(drill 0.369824)
			(layers "*.Cu" "*.Mask")
			(remove_unused_layers no)
			(net "BMC_I2C1_MINI1_SCL")
			(clearance 0.1778)
			(thermal_gap 0.1778)
		)
		(pad "AC2" thru_hole circle
			(at -18.750026 -10.599928)
			(size 0.7366 0.7366)
			(drill 0.369824)
			(layers "*.Cu" "*.Mask")
			(remove_unused_layers no)
			(net "8644_CBL_PRSNT_R_1")
			(clearance 0.1778)
			(thermal_gap 0.1778)
		)
		(pad "AC3" thru_hole circle
			(at -17.999964 -11.299952)
			(size 0.7366 0.7366)
			(drill 0.369824)
			(layers "*.Cu" "*.Mask")
			(remove_unused_layers no)
			(net "GND")
			(clearance 0.1778)
			(thermal_gap 0.1778)
		)
		(pad "AC4" thru_hole circle
			(at -17.249902 -11.999976)
			(size 0.7366 0.7366)
			(drill 0.369824)
			(layers "*.Cu" "*.Mask")
			(remove_unused_layers no)
			(net "PCIE_TX_P80")
			(clearance 0.1778)
			(thermal_gap 0.1778)
		)
		(pad "AC5" thru_hole circle
			(at -16.500094 -10.599928)
			(size 0.7366 0.7366)
			(drill 0.369824)
			(layers "*.Cu" "*.Mask")
			(remove_unused_layers no)
			(net "PCIE_TX_N80")
			(clearance 0.1778)
			(thermal_gap 0.1778)
		)
		(pad "AC6" thru_hole circle
			(at -15.750032 -11.299952)
			(size 0.7366 0.7366)
			(drill 0.369824)
			(layers "*.Cu" "*.Mask")
			(remove_unused_layers no)
			(net "GND")
			(clearance 0.1778)
			(thermal_gap 0.1778)
		)
		(pad "AC7" thru_hole circle
			(at -14.99997 -11.999976)
			(size 0.7366 0.7366)
			(drill 0.369824)
			(layers "*.Cu" "*.Mask")
			(remove_unused_layers no)
			(net "PCIE_TX_P83")
			(clearance 0.1778)
			(thermal_gap 0.1778)
		)
		(pad "AC8" thru_hole circle
			(at -14.249908 -10.599928)
			(size 0.7366 0.7366)
			(drill 0.369824)
			(layers "*.Cu" "*.Mask")
			(remove_unused_layers no)
			(net "PCIE_TX_N83")
			(clearance 0.1778)
			(thermal_gap 0.1778)
		)
		(pad "AC9" thru_hole circle
			(at -13.5001 -11.299952)
			(size 0.7366 0.7366)
			(drill 0.369824)
			(layers "*.Cu" "*.Mask")
			(remove_unused_layers no)
			(net "GND")
			(clearance 0.1778)
			(thermal_gap 0.1778)
		)
		(pad "AD1" thru_hole circle
			(at -19.500088 -15.80007)
			(size 0.7366 0.7366)
			(drill 0.369824)
			(layers "*.Cu" "*.Mask")
			(remove_unused_layers no)
			(net "8644_USB_DN1")
			(clearance 0.1778)
			(thermal_gap 0.1778)
		)
		(pad "AD2" thru_hole circle
			(at -18.750026 -14.400022)
			(size 0.7366 0.7366)
			(drill 0.369824)
			(layers "*.Cu" "*.Mask")
			(remove_unused_layers no)
			(net "8644_USB_DP1")
			(clearance 0.1778)
			(thermal_gap 0.1778)
		)
		(pad "AD3" thru_hole circle
			(at -17.999964 -15.100046)
			(size 0.7366 0.7366)
			(drill 0.369824)
			(layers "*.Cu" "*.Mask")
			(remove_unused_layers no)
			(net "GND")
			(clearance 0.1778)
			(thermal_gap 0.1778)
		)
		(pad "AD4" thru_hole circle
			(at -17.249902 -15.80007)
			(size 0.7366 0.7366)
			(drill 0.369824)
			(layers "*.Cu" "*.Mask")
			(remove_unused_layers no)
			(net "PCIE_TX_P81")
			(clearance 0.1778)
			(thermal_gap 0.1778)
		)
		(pad "AD5" thru_hole circle
			(at -16.500094 -14.400022)
			(size 0.7366 0.7366)
			(drill 0.369824)
			(layers "*.Cu" "*.Mask")
			(remove_unused_layers no)
			(net "PCIE_TX_N81")
			(clearance 0.1778)
			(thermal_gap 0.1778)
		)
		(pad "AD6" thru_hole circle
			(at -15.750032 -15.100046)
			(size 0.7366 0.7366)
			(drill 0.369824)
			(layers "*.Cu" "*.Mask")
			(remove_unused_layers no)
			(net "GND")
			(clearance 0.1778)
			(thermal_gap 0.1778)
		)
		(pad "AD7" thru_hole circle
			(at -14.99997 -15.80007)
			(size 0.7366 0.7366)
			(drill 0.369824)
			(layers "*.Cu" "*.Mask")
			(remove_unused_layers no)
			(net "PCIE_TX_P82")
			(clearance 0.1778)
			(thermal_gap 0.1778)
		)
		(pad "AD8" thru_hole circle
			(at -14.249908 -14.400022)
			(size 0.7366 0.7366)
			(drill 0.369824)
			(layers "*.Cu" "*.Mask")
			(remove_unused_layers no)
			(net "PCIE_TX_N82")
			(clearance 0.1778)
			(thermal_gap 0.1778)
		)
		(pad "AD9" thru_hole circle
			(at -13.5001 -15.100046)
			(size 0.7366 0.7366)
			(drill 0.369824)
			(layers "*.Cu" "*.Mask")
			(remove_unused_layers no)
			(net "GND")
			(clearance 0.1778)
			(thermal_gap 0.1778)
		)
		(pad "BA1" thru_hole circle
			(at -8.50011 -4.400042)
			(size 0.7366 0.7366)
			(drill 0.369824)
			(layers "*.Cu" "*.Mask")
			(remove_unused_layers no)
			(net "CLK_P_2")
			(clearance 0.1778)
			(thermal_gap 0.1778)
		)
		(pad "BA2" thru_hole circle
			(at -7.750048 -2.999994)
			(size 0.7366 0.7366)
			(drill 0.369824)
			(layers "*.Cu" "*.Mask")
			(remove_unused_layers no)
			(net "CLK_N_2")
			(clearance 0.1778)
			(thermal_gap 0.1778)
		)
		(pad "BA3" thru_hole circle
			(at -6.999986 -3.700018)
			(size 0.7366 0.7366)
			(drill 0.369824)
			(layers "*.Cu" "*.Mask")
			(remove_unused_layers no)
			(net "GND")
			(clearance 0.1778)
			(thermal_gap 0.1778)
		)
		(pad "BA4" thru_hole circle
			(at -6.249924 -4.400042)
			(size 0.7366 0.7366)
			(drill 0.369824)
			(layers "*.Cu" "*.Mask")
			(remove_unused_layers no)
			(net "PCIE_RX_P84")
			(clearance 0.1778)
			(thermal_gap 0.1778)
		)
		(pad "BA5" thru_hole circle
			(at -5.500116 -2.999994)
			(size 0.7366 0.7366)
			(drill 0.369824)
			(layers "*.Cu" "*.Mask")
			(remove_unused_layers no)
			(net "PCIE_RX_N84")
			(clearance 0.1778)
			(thermal_gap 0.1778)
		)
		(pad "BA6" thru_hole circle
			(at -4.750054 -3.700018)
			(size 0.7366 0.7366)
			(drill 0.369824)
			(layers "*.Cu" "*.Mask")
			(remove_unused_layers no)
			(net "GND")
			(clearance 0.1778)
			(thermal_gap 0.1778)
		)
		(pad "BA7" thru_hole circle
			(at -3.999992 -4.400042)
			(size 0.7366 0.7366)
			(drill 0.369824)
			(layers "*.Cu" "*.Mask")
			(remove_unused_layers no)
			(net "PCIE_RX_P87")
			(clearance 0.1778)
			(thermal_gap 0.1778)
		)
		(pad "BA8" thru_hole circle
			(at -3.24993 -2.999994)
			(size 0.7366 0.7366)
			(drill 0.369824)
			(layers "*.Cu" "*.Mask")
			(remove_unused_layers no)
			(net "PCIE_RX_N87")
			(clearance 0.1778)
			(thermal_gap 0.1778)
		)
		(pad "BA9" thru_hole circle
			(at -2.500122 -3.700018)
			(size 0.7366 0.7366)
			(drill 0.369824)
			(layers "*.Cu" "*.Mask")
			(remove_unused_layers no)
			(net "GND")
			(clearance 0.1778)
			(thermal_gap 0.1778)
		)
		(pad "BB1" thru_hole circle
			(at -8.50011 -8.199882)
			(size 0.7366 0.7366)
			(drill 0.369824)
			(layers "*.Cu" "*.Mask")
			(remove_unused_layers no)
			(net "HOST2_RST_N_C")
			(clearance 0.1778)
			(thermal_gap 0.1778)
		)
		(pad "BB2" thru_hole circle
			(at -7.750048 -6.800088)
			(size 0.7366 0.7366)
			(drill 0.369824)
			(layers "*.Cu" "*.Mask")
			(remove_unused_layers no)
			(net "8644_SDA_R_2")
			(clearance 0.1778)
			(thermal_gap 0.1778)
		)
		(pad "BB3" thru_hole circle
			(at -6.999986 -7.500112)
			(size 0.7366 0.7366)
			(drill 0.369824)
			(layers "*.Cu" "*.Mask")
			(remove_unused_layers no)
			(net "GND")
			(clearance 0.1778)
			(thermal_gap 0.1778)
		)
		(pad "BB4" thru_hole circle
			(at -6.249924 -8.199882)
			(size 0.7366 0.7366)
			(drill 0.369824)
			(layers "*.Cu" "*.Mask")
			(remove_unused_layers no)
			(net "PCIE_RX_P85")
			(clearance 0.1778)
			(thermal_gap 0.1778)
		)
		(pad "BB5" thru_hole circle
			(at -5.500116 -6.800088)
			(size 0.7366 0.7366)
			(drill 0.369824)
			(layers "*.Cu" "*.Mask")
			(remove_unused_layers no)
			(net "PCIE_RX_N85")
			(clearance 0.1778)
			(thermal_gap 0.1778)
		)
		(pad "BB6" thru_hole circle
			(at -4.750054 -7.500112)
			(size 0.7366 0.7366)
			(drill 0.369824)
			(layers "*.Cu" "*.Mask")
			(remove_unused_layers no)
			(net "GND")
			(clearance 0.1778)
			(thermal_gap 0.1778)
		)
		(pad "BB7" thru_hole circle
			(at -3.999992 -8.199882)
			(size 0.7366 0.7366)
			(drill 0.369824)
			(layers "*.Cu" "*.Mask")
			(remove_unused_layers no)
			(net "PCIE_RX_P86")
			(clearance 0.1778)
			(thermal_gap 0.1778)
		)
		(pad "BB8" thru_hole circle
			(at -3.24993 -6.800088)
			(size 0.7366 0.7366)
			(drill 0.369824)
			(layers "*.Cu" "*.Mask")
			(remove_unused_layers no)
			(net "PCIE_RX_N86")
			(clearance 0.1778)
			(thermal_gap 0.1778)
		)
		(pad "BB9" thru_hole circle
			(at -2.500122 -7.500112)
			(size 0.7366 0.7366)
			(drill 0.369824)
			(layers "*.Cu" "*.Mask")
			(remove_unused_layers no)
			(net "GND")
			(clearance 0.1778)
			(thermal_gap 0.1778)
		)
		(pad "BC1" thru_hole circle
			(at -8.50011 -11.999976)
			(size 0.7366 0.7366)
			(drill 0.369824)
			(layers "*.Cu" "*.Mask")
			(remove_unused_layers no)
			(net "BMC_I2C2_MINI2_SCL")
			(clearance 0.1778)
			(thermal_gap 0.1778)
		)
		(pad "BC2" thru_hole circle
			(at -7.750048 -10.599928)
			(size 0.7366 0.7366)
			(drill 0.369824)
			(layers "*.Cu" "*.Mask")
			(remove_unused_layers no)
			(net "8644_CBL_PRSNT_R_2")
			(clearance 0.1778)
			(thermal_gap 0.1778)
		)
		(pad "BC3" thru_hole circle
			(at -6.999986 -11.299952)
			(size 0.7366 0.7366)
			(drill 0.369824)
			(layers "*.Cu" "*.Mask")
			(remove_unused_layers no)
			(net "GND")
			(clearance 0.1778)
			(thermal_gap 0.1778)
		)
		(pad "BC4" thru_hole circle
			(at -6.249924 -11.999976)
			(size 0.7366 0.7366)
			(drill 0.369824)
			(layers "*.Cu" "*.Mask")
			(remove_unused_layers no)
			(net "PCIE_TX_P84")
			(clearance 0.1778)
			(thermal_gap 0.1778)
		)
		(pad "BC5" thru_hole circle
			(at -5.500116 -10.599928)
			(size 0.7366 0.7366)
			(drill 0.369824)
			(layers "*.Cu" "*.Mask")
			(remove_unused_layers no)
			(net "PCIE_TX_N84")
			(clearance 0.1778)
			(thermal_gap 0.1778)
		)
		(pad "BC6" thru_hole circle
			(at -4.750054 -11.299952)
			(size 0.7366 0.7366)
			(drill 0.369824)
			(layers "*.Cu" "*.Mask")
			(remove_unused_layers no)
			(net "GND")
			(clearance 0.1778)
			(thermal_gap 0.1778)
		)
		(pad "BC7" thru_hole circle
			(at -3.999992 -11.999976)
			(size 0.7366 0.7366)
			(drill 0.369824)
			(layers "*.Cu" "*.Mask")
			(remove_unused_layers no)
			(net "PCIE_TX_P87")
			(clearance 0.1778)
			(thermal_gap 0.1778)
		)
		(pad "BC8" thru_hole circle
			(at -3.24993 -10.599928)
			(size 0.7366 0.7366)
			(drill 0.369824)
			(layers "*.Cu" "*.Mask")
			(remove_unused_layers no)
			(net "PCIE_TX_N87")
			(clearance 0.1778)
			(thermal_gap 0.1778)
		)
		(pad "BC9" thru_hole circle
			(at -2.500122 -11.299952)
			(size 0.7366 0.7366)
			(drill 0.369824)
			(layers "*.Cu" "*.Mask")
			(remove_unused_layers no)
			(net "GND")
			(clearance 0.1778)
			(thermal_gap 0.1778)
		)
		(pad "BD1" thru_hole circle
			(at -8.50011 -15.80007)
			(size 0.7366 0.7366)
			(drill 0.369824)
			(layers "*.Cu" "*.Mask")
			(remove_unused_layers no)
			(net "8644_USB_DN2")
			(clearance 0.1778)
			(thermal_gap 0.1778)
		)
		(pad "BD2" thru_hole circle
			(at -7.750048 -14.400022)
			(size 0.7366 0.7366)
			(drill 0.369824)
			(layers "*.Cu" "*.Mask")
			(remove_unused_layers no)
			(net "8644_USB_DP2")
			(clearance 0.1778)
			(thermal_gap 0.1778)
		)
		(pad "BD3" thru_hole circle
			(at -6.999986 -15.100046)
			(size 0.7366 0.7366)
			(drill 0.369824)
			(layers "*.Cu" "*.Mask")
			(remove_unused_layers no)
			(net "GND")
			(clearance 0.1778)
			(thermal_gap 0.1778)
		)
		(pad "BD4" thru_hole circle
			(at -6.249924 -15.80007)
			(size 0.7366 0.7366)
			(drill 0.369824)
			(layers "*.Cu" "*.Mask")
			(remove_unused_layers no)
			(net "PCIE_TX_P85")
			(clearance 0.1778)
			(thermal_gap 0.1778)
		)
		(pad "BD5" thru_hole circle
			(at -5.500116 -14.400022)
			(size 0.7366 0.7366)
			(drill 0.369824)
			(layers "*.Cu" "*.Mask")
			(remove_unused_layers no)
			(net "PCIE_TX_N85")
			(clearance 0.1778)
			(thermal_gap 0.1778)
		)
		(pad "BD6" thru_hole circle
			(at -4.750054 -15.100046)
			(size 0.7366 0.7366)
			(drill 0.369824)
			(layers "*.Cu" "*.Mask")
			(remove_unused_layers no)
			(net "GND")
			(clearance 0.1778)
			(thermal_gap 0.1778)
		)
		(pad "BD7" thru_hole circle
			(at -3.999992 -15.80007)
			(size 0.7366 0.7366)
			(drill 0.369824)
			(layers "*.Cu" "*.Mask")
			(remove_unused_layers no)
			(net "PCIE_TX_P86")
			(clearance 0.1778)
			(thermal_gap 0.1778)
		)
		(pad "BD8" thru_hole circle
			(at -3.24993 -14.400022)
			(size 0.7366 0.7366)
			(drill 0.369824)
			(layers "*.Cu" "*.Mask")
			(remove_unused_layers no)
			(net "PCIE_TX_N86")
			(clearance 0.1778)
			(thermal_gap 0.1778)
		)
		(pad "BD9" thru_hole circle
			(at -2.500122 -15.100046)
			(size 0.7366 0.7366)
			(drill 0.369824)
			(layers "*.Cu" "*.Mask")
			(remove_unused_layers no)
			(net "GND")
			(clearance 0.1778)
			(thermal_gap 0.1778)
		)
		(pad "CA1" thru_hole circle
			(at 2.500122 -4.400042)
			(size 0.7366 0.7366)
			(drill 0.369824)
			(layers "*.Cu" "*.Mask")
			(remove_unused_layers no)
			(net "PCIE_REFCLK_H3_P_R")
			(clearance 0.1778)
			(thermal_gap 0.1778)
		)
		(pad "CA2" thru_hole circle
			(at 3.24993 -2.999994)
			(size 0.7366 0.7366)
			(drill 0.369824)
			(layers "*.Cu" "*.Mask")
			(remove_unused_layers no)
			(net "PCIE_REFCLK_H3_N_R")
			(clearance 0.1778)
			(thermal_gap 0.1778)
		)
		(pad "CA3" thru_hole circle
			(at 3.999992 -3.700018)
			(size 0.7366 0.7366)
			(drill 0.369824)
			(layers "*.Cu" "*.Mask")
			(remove_unused_layers no)
			(net "GND")
			(clearance 0.1778)
			(thermal_gap 0.1778)
		)
		(pad "CA4" thru_hole circle
			(at 4.750054 -4.400042)
			(size 0.7366 0.7366)
			(drill 0.369824)
			(layers "*.Cu" "*.Mask")
			(remove_unused_layers no)
			(net "PCIE_RX_P88")
			(clearance 0.1778)
			(thermal_gap 0.1778)
		)
	)
)
